(kicad_pcb
	(version 20241229)
	(generator "pcbnew")
	(generator_version "9.0")
	(general
		(thickness 1.62)
		(legacy_teardrops no)
	)
	(paper "A3")
	(title_block
		(title "COM Express 7 Baseboard")
		(date "2025-02-04")
		(rev "1.1.2")
		(company "Antmicro Ltd")
		(comment 1 "www.antmicro.com")
		(comment 9 "footprints 354-358 of 802")
	)
	(layers
		(0 "F.Cu" signal)
		(4 "In1.Cu" signal)
		(6 "In2.Cu" signal)
		(8 "In3.Cu" signal)
		(10 "In4.Cu" signal)
		(12 "In5.Cu" signal)
		(14 "In6.Cu" signal)
		(2 "B.Cu" signal)
		(9 "F.Adhes" user "F.Adhesive")
		(11 "B.Adhes" user "B.Adhesive")
		(13 "F.Paste" user)
		(15 "B.Paste" user)
		(5 "F.SilkS" user "F.Silkscreen")
		(7 "B.SilkS" user "B.Silkscreen")
		(1 "F.Mask" user)
		(3 "B.Mask" user)
		(17 "Dwgs.User" user "User.Drawings")
		(19 "Cmts.User" user "User.Comments")
		(21 "Eco1.User" user "User.Eco1")
		(23 "Eco2.User" user "User.Eco2")
		(25 "Edge.Cuts" user)
		(27 "Margin" user)
		(31 "F.CrtYd" user "F.Courtyard")
		(29 "B.CrtYd" user "B.Courtyard")
		(35 "F.Fab" user)
		(33 "B.Fab" user)
	)
	(footprint "antmicro-footprints:R_0201"
		(layer "F.Cu")
		(at 131.41 147.961 -90)
		(descr "Resistor SMD 0201")
		(tags "resistor SMD 0201")
		(property "Reference" "R311"
			(at 3.6 -0.29 90)
			(layer "F.SilkS")
			(effects
				(font
					(size 0.7 0.7)
					(thickness 0.15)
				)
				(justify right bottom)
			)
		)
		(property "Value" "R_0R_0201"
			(at 0 1.25 90)
			(layer "F.Fab")
			(effects
				(font
					(size 0.7 0.7)
					(thickness 0.15)
				)
				(justify right bottom)
			)
		)
		(property "Datasheet" "https://www.bourns.com/docs/product-datasheets/cr.pdf"
			(at 0 0 270)
			(layer "F.Fab")
			(hide yes)
			(effects
				(font
					(size 1.27 1.27)
					(thickness 0.15)
				)
			)
		)
		(property "Author" "Antmicro"
			(at -16.551 279.371 0)
			(layer "F.Fab")
			(hide yes)
			(effects
				(font
					(size 1 1)
					(thickness 0.15)
				)
			)
		)
		(property "License" "Apache-2.0"
			(at -16.551 279.371 0)
			(layer "F.Fab")
			(hide yes)
			(effects
				(font
					(size 1 1)
					(thickness 0.15)
				)
			)
		)
		(property "MPN" "CR0201-FX-0R00GLF"
			(at -16.551 279.371 0)
			(layer "F.Fab")
			(hide yes)
			(effects
				(font
					(size 1 1)
					(thickness 0.15)
				)
			)
		)
		(property "Manufacturer" "Bourns"
			(at -16.551 279.371 0)
			(layer "F.Fab")
			(hide yes)
			(effects
				(font
					(size 1 1)
					(thickness 0.15)
				)
			)
		)
		(property "Tolerance" "1%"
			(at -16.551 279.371 0)
			(layer "F.Fab")
			(hide yes)
			(effects
				(font
					(size 1 1)
					(thickness 0.15)
				)
			)
		)
		(property "Val" "0R"
			(at -16.551 279.371 0)
			(layer "F.Fab")
			(hide yes)
			(effects
				(font
					(size 1 1)
					(thickness 0.15)
				)
			)
		)
		(sheetname "KR to SFI #2")
		(sheetfile "kr_sfi.kicad_sch")
		(attr smd dnp)
		(fp_rect
			(start -0.7 -0.35)
			(end 0.7 0.35)
			(stroke
				(width 0.05)
				(type default)
			)
			(fill no)
			(layer "F.CrtYd")
		)
		(fp_rect
			(start -0.3 -0.15)
			(end 0.298 0.148)
			(stroke
				(width 0.15)
				(type solid)
			)
			(fill no)
			(layer "F.Fab")
		)
		(pad "" smd roundrect
			(at -0.346 0 270)
			(size 0.318 0.36)
			(layers "F.Paste")
			(roundrect_rratio 0.25)
			(teardrops
				(best_length_ratio 0.2)
				(max_length 1)
				(best_width_ratio 0.9)
				(max_width 2)
				(curved_edges yes)
				(filter_ratio 0.9)
				(enabled yes)
				(allow_two_segments yes)
				(prefer_zone_connections yes)
			)
		)
		(pad "" smd roundrect
			(at 0.344 0 270)
			(size 0.318 0.36)
			(layers "F.Paste")
			(roundrect_rratio 0.25)
			(teardrops
				(best_length_ratio 0.2)
				(max_length 1)
				(best_width_ratio 0.9)
				(max_width 2)
				(curved_edges yes)
				(filter_ratio 0.9)
				(enabled yes)
				(allow_two_segments yes)
				(prefer_zone_connections yes)
			)
		)
		(pad "1" smd roundrect
			(at -0.32 0 270)
			(size 0.46 0.4)
			(layers "F.Cu" "F.Mask")
			(roundrect_rratio 0.25)
			(net 878 "/2xSFP+/SFI1.RX+")
			(pintype "passive")
			(teardrops
				(best_length_ratio 0.2)
				(max_length 1)
				(best_width_ratio 0.9)
				(max_width 2)
				(curved_edges yes)
				(filter_ratio 0.9)
				(enabled yes)
				(allow_two_segments yes)
				(prefer_zone_connections yes)
			)
		)
		(pad "2" smd roundrect
			(at 0.32 0 270)
			(size 0.46 0.4)
			(layers "F.Cu" "F.Mask")
			(roundrect_rratio 0.25)
			(net 949 "/2xSFP+/KR to SFI #2/BYP_RX+")
			(pintype "passive")
			(teardrops
				(best_length_ratio 0.2)
				(max_length 1)
				(best_width_ratio 0.9)
				(max_width 2)
				(curved_edges yes)
				(filter_ratio 0.9)
				(enabled yes)
				(allow_two_segments yes)
				(prefer_zone_connections yes)
			)
		)
	)
	(footprint "antmicro-footprints:C_0402_1005Metric"
		(layer "F.Cu")
		(at 236.7 154.46 90)
		(descr "Capacitor SMD 0402")
		(tags "capacitor SMD 0402")
		(property "Reference" "C100"
			(at -1.4 -0.5 90)
			(layer "F.SilkS")
			(effects
				(font
					(size 0.7 0.7)
					(thickness 0.15)
				)
				(justify left bottom)
			)
		)
		(property "Value" "C_100n_0402"
			(at -1.022927 2.155213 90)
			(layer "F.Fab")
			(effects
				(font
					(size 0.7 0.7)
					(thickness 0.15)
				)
				(justify left bottom)
			)
		)
		(property "Datasheet" "https://www.murata.com/products/productdetail?partno=GRM155R61H104KE14%23"
			(at 0 0 90)
			(layer "F.Fab")
			(hide yes)
			(effects
				(font
					(size 1.27 1.27)
					(thickness 0.15)
				)
			)
		)
		(property "Author" "Antmicro"
			(at 391.16 -82.24 0)
			(layer "F.Fab")
			(hide yes)
			(effects
				(font
					(size 1 1)
					(thickness 0.15)
				)
			)
		)
		(property "Dielectric" "X5R"
			(at 391.16 -82.24 0)
			(layer "F.Fab")
			(hide yes)
			(effects
				(font
					(size 1 1)
					(thickness 0.15)
				)
			)
		)
		(property "License" "Apache-2.0"
			(at 391.16 -82.24 0)
			(layer "F.Fab")
			(hide yes)
			(effects
				(font
					(size 1 1)
					(thickness 0.15)
				)
			)
		)
		(property "MPN" "GRM155R61H104KE14D"
			(at 391.16 -82.24 0)
			(layer "F.Fab")
			(hide yes)
			(effects
				(font
					(size 1 1)
					(thickness 0.15)
				)
			)
		)
		(property "Manufacturer" "Murata"
			(at 391.16 -82.24 0)
			(layer "F.Fab")
			(hide yes)
			(effects
				(font
					(size 1 1)
					(thickness 0.15)
				)
			)
		)
		(property "Public" "False"
			(at 391.16 -82.24 0)
			(layer "F.Fab")
			(hide yes)
			(effects
				(font
					(size 1 1)
					(thickness 0.15)
				)
			)
		)
		(property "Val" "100n"
			(at 391.16 -82.24 0)
			(layer "F.Fab")
			(hide yes)
			(effects
				(font
					(size 1 1)
					(thickness 0.15)
				)
			)
		)
		(property "Voltage" "50V"
			(at 391.16 -82.24 0)
			(layer "F.Fab")
			(hide yes)
			(effects
				(font
					(size 1 1)
					(thickness 0.15)
				)
			)
		)
		(sheetname "Com Express 7 MGMT")
		(sheetfile "com_express_7_mgmt.kicad_sch")
		(attr smd)
		(fp_rect
			(start -0.925 -0.47)
			(end 0.925 0.47)
			(stroke
				(width 0.05)
				(type default)
			)
			(fill no)
			(layer "F.CrtYd")
		)
		(fp_line
			(start 0.504 -0.25)
			(end 0.504 0.248)
			(stroke
				(width 0.15)
				(type solid)
			)
			(layer "F.Fab")
		)
		(fp_line
			(start -0.494 -0.25)
			(end 0.504 -0.25)
			(stroke
				(width 0.15)
				(type solid)
			)
			(layer "F.Fab")
		)
		(fp_line
			(start 0.504 0.248)
			(end -0.494 0.248)
			(stroke
				(width 0.15)
				(type solid)
			)
			(layer "F.Fab")
		)
		(fp_line
			(start -0.494 0.248)
			(end -0.494 -0.25)
			(stroke
				(width 0.15)
				(type solid)
			)
			(layer "F.Fab")
		)
		(pad "1" smd roundrect
			(at -0.48 0 90)
			(size 0.59 0.64)
			(layers "F.Cu" "F.Mask" "F.Paste")
			(roundrect_rratio 0.25)
			(net 1 "GND")
			(pintype "passive")
			(teardrops
				(best_length_ratio 0.2)
				(max_length 1)
				(best_width_ratio 0.9)
				(max_width 2)
				(curved_edges yes)
				(filter_ratio 0.9)
				(enabled yes)
				(allow_two_segments yes)
				(prefer_zone_connections yes)
			)
		)
		(pad "2" smd roundrect
			(at 0.48 0 90)
			(size 0.59 0.64)
			(layers "F.Cu" "F.Mask" "F.Paste")
			(roundrect_rratio 0.25)
			(net 73 "+3V3_AON")
			(pintype "passive")
			(teardrops
				(best_length_ratio 0.2)
				(max_length 1)
				(best_width_ratio 0.9)
				(max_width 2)
				(curved_edges yes)
				(filter_ratio 0.9)
				(enabled yes)
				(allow_two_segments yes)
				(prefer_zone_connections yes)
			)
		)
	)
	(footprint "antmicro-footprints:R_0402_1005Metric"
		(layer "F.Cu")
		(at 134.425001 83.310001 180)
		(descr "Resistor SMD 0402")
		(tags "resistor SMD 0402")
		(property "Reference" "R232"
			(at -3.624999 -0.449999 0)
			(layer "F.SilkS")
			(effects
				(font
					(size 0.7 0.7)
					(thickness 0.15)
				)
				(justify right bottom)
			)
		)
		(property "Value" "R_0R_0402"
			(at -1.011843 1.772047 0)
			(layer "F.Fab")
			(effects
				(font
					(size 0.7 0.7)
					(thickness 0.15)
				)
				(justify right bottom)
			)
		)
		(property "Datasheet" "https://industrial.panasonic.com/cdbs/www-data/pdf/RDA0000/AOA0000C301.pdf"
			(at 0 0 180)
			(layer "F.Fab")
			(hide yes)
			(effects
				(font
					(size 1.27 1.27)
					(thickness 0.15)
				)
			)
		)
		(property "Author" "Antmicro"
			(at 268.850002 166.620002 0)
			(layer "F.Fab")
			(hide yes)
			(effects
				(font
					(size 1 1)
					(thickness 0.15)
				)
			)
		)
		(property "Current" "1A"
			(at 268.850002 166.620002 0)
			(layer "F.Fab")
			(hide yes)
			(effects
				(font
					(size 1 1)
					(thickness 0.15)
				)
			)
		)
		(property "License" "Apache-2.0"
			(at 268.850002 166.620002 0)
			(layer "F.Fab")
			(hide yes)
			(effects
				(font
					(size 1 1)
					(thickness 0.15)
				)
			)
		)
		(property "MPN" "ERJ2GE0R00X"
			(at 268.850002 166.620002 0)
			(layer "F.Fab")
			(hide yes)
			(effects
				(font
					(size 1 1)
					(thickness 0.15)
				)
			)
		)
		(property "Manufacturer" "Panasonic"
			(at 268.850002 166.620002 0)
			(layer "F.Fab")
			(hide yes)
			(effects
				(font
					(size 1 1)
					(thickness 0.15)
				)
			)
		)
		(property "Public" "False"
			(at 268.850002 166.620002 0)
			(layer "F.Fab")
			(hide yes)
			(effects
				(font
					(size 1 1)
					(thickness 0.15)
				)
			)
		)
		(property "Tolerance" ""
			(at 268.850002 166.620002 0)
			(layer "F.Fab")
			(hide yes)
			(effects
				(font
					(size 1 1)
					(thickness 0.15)
				)
			)
		)
		(property "Val" "0R"
			(at 268.850002 166.620002 0)
			(layer "F.Fab")
			(hide yes)
			(effects
				(font
					(size 1 1)
					(thickness 0.15)
				)
			)
		)
		(sheetname "GPIO expander")
		(sheetfile "gpio_exp.kicad_sch")
		(attr smd)
		(fp_rect
			(start -0.925 -0.47)
			(end 0.925 0.47)
			(stroke
				(width 0.05)
				(type default)
			)
			(fill no)
			(layer "F.CrtYd")
		)
		(fp_rect
			(start -0.5 -0.25)
			(end 0.5 0.25)
			(stroke
				(width 0.15)
				(type solid)
			)
			(fill no)
			(layer "F.Fab")
		)
		(pad "1" smd roundrect
			(at -0.48 0 180)
			(size 0.59 0.64)
			(layers "F.Cu" "F.Mask" "F.Paste")
			(roundrect_rratio 0.25)
			(net 1 "GND")
			(pintype "passive")
			(teardrops
				(best_length_ratio 0.2)
				(max_length 1)
				(best_width_ratio 0.9)
				(max_width 2)
				(curved_edges yes)
				(filter_ratio 0.9)
				(enabled yes)
				(allow_two_segments yes)
				(prefer_zone_connections yes)
			)
		)
		(pad "2" smd roundrect
			(at 0.48 0 180)
			(size 0.59 0.64)
			(layers "F.Cu" "F.Mask" "F.Paste")
			(roundrect_rratio 0.25)
			(net 633 "Net-(U41-A0)")
			(pintype "passive")
			(teardrops
				(best_length_ratio 0.2)
				(max_length 1)
				(best_width_ratio 0.9)
				(max_width 2)
				(curved_edges yes)
				(filter_ratio 0.9)
				(enabled yes)
				(allow_two_segments yes)
				(prefer_zone_connections yes)
			)
		)
	)
	(footprint "antmicro-footprints:R_0402_1005Metric"
		(layer "F.Cu")
		(at 126.425 88.06 180)
		(descr "Resistor SMD 0402")
		(tags "resistor SMD 0402")
		(property "Reference" "R243"
			(at -1.575 -6.4 0)
			(layer "F.SilkS")
			(effects
				(font
					(size 0.7 0.7)
					(thickness 0.15)
				)
				(justify right bottom)
			)
		)
		(property "Value" "R_0R_0402"
			(at -1.011843 1.772047 0)
			(layer "F.Fab")
			(effects
				(font
					(size 0.7 0.7)
					(thickness 0.15)
				)
				(justify right bottom)
			)
		)
		(property "Datasheet" "https://industrial.panasonic.com/cdbs/www-data/pdf/RDA0000/AOA0000C301.pdf"
			(at 0 0 180)
			(layer "F.Fab")
			(hide yes)
			(effects
				(font
					(size 1.27 1.27)
					(thickness 0.15)
				)
			)
		)
		(property "Author" "Antmicro"
			(at 252.85 176.12 0)
			(layer "F.Fab")
			(hide yes)
			(effects
				(font
					(size 1 1)
					(thickness 0.15)
				)
			)
		)
		(property "Current" "1A"
			(at 252.85 176.12 0)
			(layer "F.Fab")
			(hide yes)
			(effects
				(font
					(size 1 1)
					(thickness 0.15)
				)
			)
		)
		(property "License" "Apache-2.0"
			(at 252.85 176.12 0)
			(layer "F.Fab")
			(hide yes)
			(effects
				(font
					(size 1 1)
					(thickness 0.15)
				)
			)
		)
		(property "MPN" "ERJ2GE0R00X"
			(at 252.85 176.12 0)
			(layer "F.Fab")
			(hide yes)
			(effects
				(font
					(size 1 1)
					(thickness 0.15)
				)
			)
		)
		(property "Manufacturer" "Panasonic"
			(at 252.85 176.12 0)
			(layer "F.Fab")
			(hide yes)
			(effects
				(font
					(size 1 1)
					(thickness 0.15)
				)
			)
		)
		(property "Public" "False"
			(at 252.85 176.12 0)
			(layer "F.Fab")
			(hide yes)
			(effects
				(font
					(size 1 1)
					(thickness 0.15)
				)
			)
		)
		(property "Tolerance" ""
			(at 252.85 176.12 0)
			(layer "F.Fab")
			(hide yes)
			(effects
				(font
					(size 1 1)
					(thickness 0.15)
				)
			)
		)
		(property "Val" "0R"
			(at 252.85 176.12 0)
			(layer "F.Fab")
			(hide yes)
			(effects
				(font
					(size 1 1)
					(thickness 0.15)
				)
			)
		)
		(sheetname "GPIO expander")
		(sheetfile "gpio_exp.kicad_sch")
		(attr smd)
		(fp_rect
			(start -0.925 -0.47)
			(end 0.925 0.47)
			(stroke
				(width 0.05)
				(type default)
			)
			(fill no)
			(layer "F.CrtYd")
		)
		(fp_rect
			(start -0.5 -0.25)
			(end 0.5 0.25)
			(stroke
				(width 0.15)
				(type solid)
			)
			(fill no)
			(layer "F.Fab")
		)
		(pad "1" smd roundrect
			(at -0.48 0 180)
			(size 0.59 0.64)
			(layers "F.Cu" "F.Mask" "F.Paste")
			(roundrect_rratio 0.25)
			(net 644 "Net-(U41-IO0_5)")
			(pintype "passive")
			(teardrops
				(best_length_ratio 0.2)
				(max_length 1)
				(best_width_ratio 0.9)
				(max_width 2)
				(curved_edges yes)
				(filter_ratio 0.9)
				(enabled yes)
				(allow_two_segments yes)
				(prefer_zone_connections yes)
			)
		)
		(pad "2" smd roundrect
			(at 0.48 0 180)
			(size 0.59 0.64)
			(layers "F.Cu" "F.Mask" "F.Paste")
			(roundrect_rratio 0.25)
			(net 945 "/GPIO expander/GPIOEX5")
			(pintype "passive")
			(teardrops
				(best_length_ratio 0.2)
				(max_length 1)
				(best_width_ratio 0.9)
				(max_width 2)
				(curved_edges yes)
				(filter_ratio 0.9)
				(enabled yes)
				(allow_two_segments yes)
				(prefer_zone_connections yes)
			)
		)
	)
	(footprint "antmicro-footprints:R_0402_1005Metric"
		(layer "F.Cu")
		(at 122.05 89.96 180)
		(descr "Resistor SMD 0402")
		(tags "resistor SMD 0402")
		(property "Reference" "R29"
			(at -2.95 -0.44 0)
			(layer "F.SilkS")
			(effects
				(font
					(size 0.7 0.7)
					(thickness 0.15)
				)
				(justify right bottom)
			)
		)
		(property "Value" "R_0R_0402"
			(at -1.011843 1.772047 0)
			(layer "F.Fab")
			(effects
				(font
					(size 0.7 0.7)
					(thickness 0.15)
				)
				(justify right bottom)
			)
		)
		(property "Datasheet" "https://industrial.panasonic.com/cdbs/www-data/pdf/RDA0000/AOA0000C301.pdf"
			(at 0 0 180)
			(layer "F.Fab")
			(hide yes)
			(effects
				(font
					(size 1.27 1.27)
					(thickness 0.15)
				)
			)
		)
		(property "Author" "Antmicro"
			(at 244.1 179.92 0)
			(layer "F.Fab")
			(hide yes)
			(effects
				(font
					(size 1 1)
					(thickness 0.15)
				)
			)
		)
		(property "Current" "1A"
			(at 244.1 179.92 0)
			(layer "F.Fab")
			(hide yes)
			(effects
				(font
					(size 1 1)
					(thickness 0.15)
				)
			)
		)
		(property "License" "Apache-2.0"
			(at 244.1 179.92 0)
			(layer "F.Fab")
			(hide yes)
			(effects
				(font
					(size 1 1)
					(thickness 0.15)
				)
			)
		)
		(property "MPN" "ERJ2GE0R00X"
			(at 244.1 179.92 0)
			(layer "F.Fab")
			(hide yes)
			(effects
				(font
					(size 1 1)
					(thickness 0.15)
				)
			)
		)
		(property "Manufacturer" "Panasonic"
			(at 244.1 179.92 0)
			(layer "F.Fab")
			(hide yes)
			(effects
				(font
					(size 1 1)
					(thickness 0.15)
				)
			)
		)
		(property "Public" "False"
			(at 244.1 179.92 0)
			(layer "F.Fab")
			(hide yes)
			(effects
				(font
					(size 1 1)
					(thickness 0.15)
				)
			)
		)
		(property "Tolerance" ""
			(at 244.1 179.92 0)
			(layer "F.Fab")
			(hide yes)
			(effects
				(font
					(size 1 1)
					(thickness 0.15)
				)
			)
		)
		(property "Val" "0R"
			(at 244.1 179.92 0)
			(layer "F.Fab")
			(hide yes)
			(effects
				(font
					(size 1 1)
					(thickness 0.15)
				)
			)
		)
		(sheetname "2xUSB3.0+RJ45")
		(sheetfile "usb3+rj45.kicad_sch")
		(attr smd)
		(fp_rect
			(start -0.925 -0.47)
			(end 0.925 0.47)
			(stroke
				(width 0.05)
				(type default)
			)
			(fill no)
			(layer "F.CrtYd")
		)
		(fp_rect
			(start -0.5 -0.25)
			(end 0.5 0.25)
			(stroke
				(width 0.15)
				(type solid)
			)
			(fill no)
			(layer "F.Fab")
		)
		(pad "1" smd roundrect
			(at -0.48 0 180)
			(size 0.59 0.64)
			(layers "F.Cu" "F.Mask" "F.Paste")
			(roundrect_rratio 0.25)
			(net 942 "/2xUSB3.0+RJ45/EN_2")
			(pintype "passive")
			(teardrops
				(best_length_ratio 0.2)
				(max_length 1)
				(best_width_ratio 0.9)
				(max_width 2)
				(curved_edges yes)
				(filter_ratio 0.9)
				(enabled yes)
				(allow_two_segments yes)
				(prefer_zone_connections yes)
			)
		)
		(pad "2" smd roundrect
			(at 0.48 0 180)
			(size 0.59 0.64)
			(layers "F.Cu" "F.Mask" "F.Paste")
			(roundrect_rratio 0.25)
			(net 556 "/2xUSB3.0+RJ45/EN_2B")
			(pintype "passive")
			(teardrops
				(best_length_ratio 0.2)
				(max_length 1)
				(best_width_ratio 0.9)
				(max_width 2)
				(curved_edges yes)
				(filter_ratio 0.9)
				(enabled yes)
				(allow_two_segments yes)
				(prefer_zone_connections yes)
			)
		)
	)
)
